(kicad_pcb
	(version 20260206)
	(generator "pcbnew")
	(generator_version "10.0")
	(general
		(thickness 1.6)
		(legacy_teardrops no)
	)
	(paper "A4")
	(title_block
		(title "12092022_DA0F0TMDCD0_F0T_Management_Board_D_brd_V3_OCP.brd")
		(comment 1 "Grand Teton / footprints 13-18 of 1440")
	)
	(layers
		(0 "F.Cu" signal "TOP")
		(4 "In1.Cu" signal "GND")
		(6 "In2.Cu" signal "IN1")
		(8 "In3.Cu" signal "GND1")
		(10 "In4.Cu" signal "IN2")
		(12 "In5.Cu" signal "VCC")
		(14 "In6.Cu" signal "VCC1")
		(16 "In7.Cu" signal "IN3")
		(18 "In8.Cu" signal "GND2")
		(20 "In9.Cu" signal "IN4")
		(22 "In10.Cu" signal "GND3")
		(2 "B.Cu" signal "BOTTOM")
		(9 "F.Adhes" user "F.Adhesive")
		(11 "B.Adhes" user "B.Adhesive")
		(13 "F.Paste" user "Package Geometry/Pastemask Top")
		(15 "B.Paste" user "Package Geometry/Pastemask Bottom")
		(5 "F.SilkS" user "Ref Des/Silkscreen Top")
		(7 "B.SilkS" user "Ref Des/Silkscreen Bottom")
		(1 "F.Mask" user "Board Geometry/Soldermask Top")
		(3 "B.Mask" user "Board Geometry/Soldermask Bottom")
		(17 "Dwgs.User" user "User.Drawings")
		(19 "Cmts.User" user "User.Comments")
		(21 "Eco1.User" user "User.Eco1")
		(23 "Eco2.User" user "User.Eco2")
		(25 "Edge.Cuts" user "Board Geometry/Outline")
		(27 "Margin" user)
		(31 "F.CrtYd" user "Package Geometry/Place Bound Top")
		(29 "B.CrtYd" user "Package Geometry/Place Bound Bottom")
		(35 "F.Fab" user "Ref Des/Assembly Top")
		(33 "B.Fab" user "Ref Des/Assembly Bottom")
	)
	(footprint ""
		(layer "F.Cu")
		(at 68.961 -101.473)
		(property "Reference" "R126"
			(at 0 0 0)
			(layer "F.SilkS")
			(hide yes)
			(effects
				(font
					(size 1.27 1.27)
				)
			)
		)
		(property "Value" ""
			(at 0 0 0)
			(layer "F.Fab")
			(effects
				(font
					(size 1.27 1.27)
				)
			)
		)
		(duplicate_pad_numbers_are_jumpers no)
		(fp_line
			(start -0.7874 -0.4064)
			(end 0.7874 -0.4064)
			(stroke
				(width 0.1524)
				(type default)
			)
			(layer "F.SilkS")
		)
		(fp_line
			(start -0.7874 0.4064)
			(end -0.7874 -0.4064)
			(stroke
				(width 0.1524)
				(type default)
			)
			(layer "F.SilkS")
		)
		(fp_line
			(start 0.7874 -0.4064)
			(end 0.7874 0.4064)
			(stroke
				(width 0.1524)
				(type default)
			)
			(layer "F.SilkS")
		)
		(fp_line
			(start 0.7874 0.4064)
			(end -0.7874 0.4064)
			(stroke
				(width 0.1524)
				(type default)
			)
			(layer "F.SilkS")
		)
		(fp_line
			(start -0.67945 -0.305054)
			(end -0.12065 -0.305054)
			(stroke
				(width 0.1)
				(type default)
			)
			(layer "F.Fab")
		)
		(fp_line
			(start -0.67945 0.3048)
			(end -0.67945 -0.305054)
			(stroke
				(width 0.1)
				(type default)
			)
			(layer "F.Fab")
		)
		(fp_line
			(start -0.12065 -0.305054)
			(end -0.12065 -0.2794)
			(stroke
				(width 0.1)
				(type default)
			)
			(layer "F.Fab")
		)
		(fp_line
			(start -0.12065 -0.2794)
			(end 0.12065 -0.2794)
			(stroke
				(width 0.1)
				(type default)
			)
			(layer "F.Fab")
		)
		(fp_line
			(start -0.12065 0.2794)
			(end -0.12065 0.3048)
			(stroke
				(width 0.1)
				(type default)
			)
			(layer "F.Fab")
		)
		(fp_line
			(start -0.12065 0.3048)
			(end -0.67945 0.3048)
			(stroke
				(width 0.1)
				(type default)
			)
			(layer "F.Fab")
		)
		(fp_line
			(start 0.120396 0.2794)
			(end -0.12065 0.2794)
			(stroke
				(width 0.1)
				(type default)
			)
			(layer "F.Fab")
		)
		(fp_line
			(start 0.120396 0.3048)
			(end 0.120396 0.2794)
			(stroke
				(width 0.1)
				(type default)
			)
			(layer "F.Fab")
		)
		(fp_line
			(start 0.12065 -0.3048)
			(end 0.67945 -0.3048)
			(stroke
				(width 0.1)
				(type default)
			)
			(layer "F.Fab")
		)
		(fp_line
			(start 0.12065 -0.2794)
			(end 0.12065 -0.3048)
			(stroke
				(width 0.1)
				(type default)
			)
			(layer "F.Fab")
		)
		(fp_line
			(start 0.67945 -0.3048)
			(end 0.67945 0.3048)
			(stroke
				(width 0.1)
				(type default)
			)
			(layer "F.Fab")
		)
		(fp_line
			(start 0.67945 0.3048)
			(end 0.120396 0.3048)
			(stroke
				(width 0.1)
				(type default)
			)
			(layer "F.Fab")
		)
		(pad "1" smd circle
			(at -0.40005 0)
			(size 0 0)
			(layers "F.Cu" "F.Mask" "F.Paste")
			(net "SMB_PCH_TPM_SDA")
		)
		(pad "2" smd circle
			(at 0.40005 0)
			(size 0 0)
			(layers "F.Cu" "F.Mask" "F.Paste")
			(net "P3V3_AUX")
		)
	)
	(footprint ""
		(layer "F.Cu")
		(at 8.9662 -54.5338 180)
		(property "Reference" "R868"
			(at 0 0 180)
			(layer "F.SilkS")
			(hide yes)
			(effects
				(font
					(size 1.27 1.27)
				)
			)
		)
		(property "Value" ""
			(at 0 0 180)
			(layer "F.Fab")
			(effects
				(font
					(size 1.27 1.27)
				)
			)
		)
		(duplicate_pad_numbers_are_jumpers no)
		(fp_line
			(start 0.7874 0.4064)
			(end -0.7874 0.4064)
			(stroke
				(width 0.1524)
				(type default)
			)
			(layer "F.SilkS")
		)
		(fp_line
			(start 0.7874 -0.4064)
			(end 0.7874 0.4064)
			(stroke
				(width 0.1524)
				(type default)
			)
			(layer "F.SilkS")
		)
		(fp_line
			(start -0.7874 0.4064)
			(end -0.7874 -0.4064)
			(stroke
				(width 0.1524)
				(type default)
			)
			(layer "F.SilkS")
		)
		(fp_line
			(start -0.7874 -0.4064)
			(end 0.7874 -0.4064)
			(stroke
				(width 0.1524)
				(type default)
			)
			(layer "F.SilkS")
		)
		(fp_line
			(start 0.67945 0.3048)
			(end 0.120396 0.3048)
			(stroke
				(width 0.1)
				(type default)
			)
			(layer "F.Fab")
		)
		(fp_line
			(start 0.67945 -0.3048)
			(end 0.67945 0.3048)
			(stroke
				(width 0.1)
				(type default)
			)
			(layer "F.Fab")
		)
		(fp_line
			(start 0.12065 -0.2794)
			(end 0.12065 -0.3048)
			(stroke
				(width 0.1)
				(type default)
			)
			(layer "F.Fab")
		)
		(fp_line
			(start 0.12065 -0.3048)
			(end 0.67945 -0.3048)
			(stroke
				(width 0.1)
				(type default)
			)
			(layer "F.Fab")
		)
		(fp_line
			(start 0.120396 0.3048)
			(end 0.120396 0.2794)
			(stroke
				(width 0.1)
				(type default)
			)
			(layer "F.Fab")
		)
		(fp_line
			(start 0.120396 0.2794)
			(end -0.12065 0.2794)
			(stroke
				(width 0.1)
				(type default)
			)
			(layer "F.Fab")
		)
		(fp_line
			(start -0.12065 0.3048)
			(end -0.67945 0.3048)
			(stroke
				(width 0.1)
				(type default)
			)
			(layer "F.Fab")
		)
		(fp_line
			(start -0.12065 0.2794)
			(end -0.12065 0.3048)
			(stroke
				(width 0.1)
				(type default)
			)
			(layer "F.Fab")
		)
		(fp_line
			(start -0.12065 -0.2794)
			(end 0.12065 -0.2794)
			(stroke
				(width 0.1)
				(type default)
			)
			(layer "F.Fab")
		)
		(fp_line
			(start -0.12065 -0.305054)
			(end -0.12065 -0.2794)
			(stroke
				(width 0.1)
				(type default)
			)
			(layer "F.Fab")
		)
		(fp_line
			(start -0.67945 0.3048)
			(end -0.67945 -0.305054)
			(stroke
				(width 0.1)
				(type default)
			)
			(layer "F.Fab")
		)
		(fp_line
			(start -0.67945 -0.305054)
			(end -0.12065 -0.305054)
			(stroke
				(width 0.1)
				(type default)
			)
			(layer "F.Fab")
		)
		(pad "1" smd circle
			(at -0.40005 0 180)
			(size 0 0)
			(layers "F.Cu" "F.Mask" "F.Paste")
			(net "PWRGD_P5V_AUX_R")
		)
		(pad "2" smd circle
			(at 0.40005 0 180)
			(size 0 0)
			(layers "F.Cu" "F.Mask" "F.Paste")
			(net "EN_P3V3_R1")
		)
	)
	(footprint ""
		(layer "F.Cu")
		(at 15.3416 -47.8536 -90)
		(property "Reference" "C296"
			(at 0 0 270)
			(layer "F.SilkS")
			(hide yes)
			(effects
				(font
					(size 1.27 1.27)
				)
			)
		)
		(property "Value" ""
			(at 0 0 270)
			(layer "F.Fab")
			(effects
				(font
					(size 1.27 1.27)
				)
			)
		)
		(duplicate_pad_numbers_are_jumpers no)
		(fp_line
			(start -0.7874 0.4064)
			(end -0.7874 -0.4064)
			(stroke
				(width 0.1524)
				(type default)
			)
			(layer "F.SilkS")
		)
		(fp_line
			(start 0.7874 0.4064)
			(end -0.7874 0.4064)
			(stroke
				(width 0.1524)
				(type default)
			)
			(layer "F.SilkS")
		)
		(fp_line
			(start -0.7874 -0.4064)
			(end 0.7874 -0.4064)
			(stroke
				(width 0.1524)
				(type default)
			)
			(layer "F.SilkS")
		)
		(fp_line
			(start 0.7874 -0.4064)
			(end 0.7874 0.4064)
			(stroke
				(width 0.1524)
				(type default)
			)
			(layer "F.SilkS")
		)
		(fp_line
			(start -0.67945 0.3048)
			(end -0.67945 -0.305054)
			(stroke
				(width 0.1)
				(type default)
			)
			(layer "F.Fab")
		)
		(fp_line
			(start -0.12065 0.3048)
			(end -0.67945 0.3048)
			(stroke
				(width 0.1)
				(type default)
			)
			(layer "F.Fab")
		)
		(fp_line
			(start 0.120396 0.3048)
			(end 0.120396 0.2794)
			(stroke
				(width 0.1)
				(type default)
			)
			(layer "F.Fab")
		)
		(fp_line
			(start 0.67945 0.3048)
			(end 0.120396 0.3048)
			(stroke
				(width 0.1)
				(type default)
			)
			(layer "F.Fab")
		)
		(fp_line
			(start -0.12065 0.2794)
			(end -0.12065 0.3048)
			(stroke
				(width 0.1)
				(type default)
			)
			(layer "F.Fab")
		)
		(fp_line
			(start 0.120396 0.2794)
			(end -0.12065 0.2794)
			(stroke
				(width 0.1)
				(type default)
			)
			(layer "F.Fab")
		)
		(fp_line
			(start -0.12065 -0.2794)
			(end 0.12065 -0.2794)
			(stroke
				(width 0.1)
				(type default)
			)
			(layer "F.Fab")
		)
		(fp_line
			(start 0.12065 -0.2794)
			(end 0.12065 -0.3048)
			(stroke
				(width 0.1)
				(type default)
			)
			(layer "F.Fab")
		)
		(fp_line
			(start 0.12065 -0.3048)
			(end 0.67945 -0.3048)
			(stroke
				(width 0.1)
				(type default)
			)
			(layer "F.Fab")
		)
		(fp_line
			(start 0.67945 -0.3048)
			(end 0.67945 0.3048)
			(stroke
				(width 0.1)
				(type default)
			)
			(layer "F.Fab")
		)
		(fp_line
			(start -0.67945 -0.305054)
			(end -0.12065 -0.305054)
			(stroke
				(width 0.1)
				(type default)
			)
			(layer "F.Fab")
		)
		(fp_line
			(start -0.12065 -0.305054)
			(end -0.12065 -0.2794)
			(stroke
				(width 0.1)
				(type default)
			)
			(layer "F.Fab")
		)
		(pad "1" smd circle
			(at -0.40005 0 270)
			(size 0 0)
			(layers "F.Cu" "F.Mask" "F.Paste")
			(net "P3V3_LDO")
		)
		(pad "2" smd circle
			(at 0.40005 0 270)
			(size 0 0)
			(layers "F.Cu" "F.Mask" "F.Paste")
			(net "GND")
		)
	)
	(footprint ""
		(layer "F.Cu")
		(at 70.8025 -31.3055)
		(property "Reference" "R709"
			(at 0 0 0)
			(layer "F.SilkS")
			(hide yes)
			(effects
				(font
					(size 1.27 1.27)
				)
			)
		)
		(property "Value" ""
			(at 0 0 0)
			(layer "F.Fab")
			(effects
				(font
					(size 1.27 1.27)
				)
			)
		)
		(duplicate_pad_numbers_are_jumpers no)
		(fp_line
			(start -0.7874 -0.4064)
			(end 0.7874 -0.4064)
			(stroke
				(width 0.1524)
				(type default)
			)
			(layer "F.SilkS")
		)
		(fp_line
			(start -0.7874 0.4064)
			(end -0.7874 -0.4064)
			(stroke
				(width 0.1524)
				(type default)
			)
			(layer "F.SilkS")
		)
		(fp_line
			(start 0.7874 -0.4064)
			(end 0.7874 0.4064)
			(stroke
				(width 0.1524)
				(type default)
			)
			(layer "F.SilkS")
		)
		(fp_line
			(start 0.7874 0.4064)
			(end -0.7874 0.4064)
			(stroke
				(width 0.1524)
				(type default)
			)
			(layer "F.SilkS")
		)
		(fp_line
			(start -0.67945 -0.305054)
			(end -0.12065 -0.305054)
			(stroke
				(width 0.1)
				(type default)
			)
			(layer "F.Fab")
		)
		(fp_line
			(start -0.67945 0.3048)
			(end -0.67945 -0.305054)
			(stroke
				(width 0.1)
				(type default)
			)
			(layer "F.Fab")
		)
		(fp_line
			(start -0.12065 -0.305054)
			(end -0.12065 -0.2794)
			(stroke
				(width 0.1)
				(type default)
			)
			(layer "F.Fab")
		)
		(fp_line
			(start -0.12065 -0.2794)
			(end 0.12065 -0.2794)
			(stroke
				(width 0.1)
				(type default)
			)
			(layer "F.Fab")
		)
		(fp_line
			(start -0.12065 0.2794)
			(end -0.12065 0.3048)
			(stroke
				(width 0.1)
				(type default)
			)
			(layer "F.Fab")
		)
		(fp_line
			(start -0.12065 0.3048)
			(end -0.67945 0.3048)
			(stroke
				(width 0.1)
				(type default)
			)
			(layer "F.Fab")
		)
		(fp_line
			(start 0.120396 0.2794)
			(end -0.12065 0.2794)
			(stroke
				(width 0.1)
				(type default)
			)
			(layer "F.Fab")
		)
		(fp_line
			(start 0.120396 0.3048)
			(end 0.120396 0.2794)
			(stroke
				(width 0.1)
				(type default)
			)
			(layer "F.Fab")
		)
		(fp_line
			(start 0.12065 -0.3048)
			(end 0.67945 -0.3048)
			(stroke
				(width 0.1)
				(type default)
			)
			(layer "F.Fab")
		)
		(fp_line
			(start 0.12065 -0.2794)
			(end 0.12065 -0.3048)
			(stroke
				(width 0.1)
				(type default)
			)
			(layer "F.Fab")
		)
		(fp_line
			(start 0.67945 -0.3048)
			(end 0.67945 0.3048)
			(stroke
				(width 0.1)
				(type default)
			)
			(layer "F.Fab")
		)
		(fp_line
			(start 0.67945 0.3048)
			(end 0.120396 0.3048)
			(stroke
				(width 0.1)
				(type default)
			)
			(layer "F.Fab")
		)
		(pad "1" smd circle
			(at -0.40005 0)
			(size 0 0)
			(layers "F.Cu" "F.Mask" "F.Paste")
			(net "P3V3_RGM")
		)
		(pad "2" smd circle
			(at 0.40005 0)
			(size 0 0)
			(layers "F.Cu" "F.Mask" "F.Paste")
			(net "PWRGD_P3V3_RGM_R")
		)
	)
	(footprint ""
		(layer "F.Cu")
		(at 30.1752 -90.3478 90)
		(property "Reference" "R748"
			(at 0 0 90)
			(layer "F.SilkS")
			(hide yes)
			(effects
				(font
					(size 1.27 1.27)
				)
			)
		)
		(property "Value" ""
			(at 0 0 90)
			(layer "F.Fab")
			(effects
				(font
					(size 1.27 1.27)
				)
			)
		)
		(duplicate_pad_numbers_are_jumpers no)
		(fp_line
			(start 0.7874 -0.4064)
			(end 0.7874 0.4064)
			(stroke
				(width 0.1524)
				(type default)
			)
			(layer "F.SilkS")
		)
		(fp_line
			(start -0.7874 -0.4064)
			(end 0.7874 -0.4064)
			(stroke
				(width 0.1524)
				(type default)
			)
			(layer "F.SilkS")
		)
		(fp_line
			(start 0.7874 0.4064)
			(end -0.7874 0.4064)
			(stroke
				(width 0.1524)
				(type default)
			)
			(layer "F.SilkS")
		)
		(fp_line
			(start -0.7874 0.4064)
			(end -0.7874 -0.4064)
			(stroke
				(width 0.1524)
				(type default)
			)
			(layer "F.SilkS")
		)
		(fp_line
			(start -0.12065 -0.305054)
			(end -0.12065 -0.2794)
			(stroke
				(width 0.1)
				(type default)
			)
			(layer "F.Fab")
		)
		(fp_line
			(start -0.67945 -0.305054)
			(end -0.12065 -0.305054)
			(stroke
				(width 0.1)
				(type default)
			)
			(layer "F.Fab")
		)
		(fp_line
			(start 0.67945 -0.3048)
			(end 0.67945 0.3048)
			(stroke
				(width 0.1)
				(type default)
			)
			(layer "F.Fab")
		)
		(fp_line
			(start 0.12065 -0.3048)
			(end 0.67945 -0.3048)
			(stroke
				(width 0.1)
				(type default)
			)
			(layer "F.Fab")
		)
		(fp_line
			(start 0.12065 -0.2794)
			(end 0.12065 -0.3048)
			(stroke
				(width 0.1)
				(type default)
			)
			(layer "F.Fab")
		)
		(fp_line
			(start -0.12065 -0.2794)
			(end 0.12065 -0.2794)
			(stroke
				(width 0.1)
				(type default)
			)
			(layer "F.Fab")
		)
		(fp_line
			(start 0.120396 0.2794)
			(end -0.12065 0.2794)
			(stroke
				(width 0.1)
				(type default)
			)
			(layer "F.Fab")
		)
		(fp_line
			(start -0.12065 0.2794)
			(end -0.12065 0.3048)
			(stroke
				(width 0.1)
				(type default)
			)
			(layer "F.Fab")
		)
		(fp_line
			(start 0.67945 0.3048)
			(end 0.120396 0.3048)
			(stroke
				(width 0.1)
				(type default)
			)
			(layer "F.Fab")
		)
		(fp_line
			(start 0.120396 0.3048)
			(end 0.120396 0.2794)
			(stroke
				(width 0.1)
				(type default)
			)
			(layer "F.Fab")
		)
		(fp_line
			(start -0.12065 0.3048)
			(end -0.67945 0.3048)
			(stroke
				(width 0.1)
				(type default)
			)
			(layer "F.Fab")
		)
		(fp_line
			(start -0.67945 0.3048)
			(end -0.67945 -0.305054)
			(stroke
				(width 0.1)
				(type default)
			)
			(layer "F.Fab")
		)
		(pad "1" smd circle
			(at -0.40005 0 90)
			(size 0 0)
			(layers "F.Cu" "F.Mask" "F.Paste")
			(net "PU_FPGA_NCONFIG")
		)
		(pad "2" smd circle
			(at 0.40005 0 90)
			(size 0 0)
			(layers "F.Cu" "F.Mask" "F.Paste")
			(net "RST_ROT_CPU_N")
		)
	)
	(footprint ""
		(layer "F.Cu")
		(at 40.132 -56.896 180)
		(property "Reference" "R406"
			(at 0 0 180)
			(layer "F.SilkS")
			(hide yes)
			(effects
				(font
					(size 1.27 1.27)
				)
			)
		)
		(property "Value" ""
			(at 0 0 180)
			(layer "F.Fab")
			(effects
				(font
					(size 1.27 1.27)
				)
			)
		)
		(duplicate_pad_numbers_are_jumpers no)
		(fp_line
			(start 0.7874 0.4064)
			(end -0.7874 0.4064)
			(stroke
				(width 0.1524)
				(type default)
			)
			(layer "F.SilkS")
		)
		(fp_line
			(start 0.7874 -0.4064)
			(end 0.7874 0.4064)
			(stroke
				(width 0.1524)
				(type default)
			)
			(layer "F.SilkS")
		)
		(fp_line
			(start -0.7874 0.4064)
			(end -0.7874 -0.4064)
			(stroke
				(width 0.1524)
				(type default)
			)
			(layer "F.SilkS")
		)
		(fp_line
			(start -0.7874 -0.4064)
			(end 0.7874 -0.4064)
			(stroke
				(width 0.1524)
				(type default)
			)
			(layer "F.SilkS")
		)
		(fp_line
			(start 0.67945 0.3048)
			(end 0.120396 0.3048)
			(stroke
				(width 0.1)
				(type default)
			)
			(layer "F.Fab")
		)
		(fp_line
			(start 0.67945 -0.3048)
			(end 0.67945 0.3048)
			(stroke
				(width 0.1)
				(type default)
			)
			(layer "F.Fab")
		)
		(fp_line
			(start 0.12065 -0.2794)
			(end 0.12065 -0.3048)
			(stroke
				(width 0.1)
				(type default)
			)
			(layer "F.Fab")
		)
		(fp_line
			(start 0.12065 -0.3048)
			(end 0.67945 -0.3048)
			(stroke
				(width 0.1)
				(type default)
			)
			(layer "F.Fab")
		)
		(fp_line
			(start 0.120396 0.3048)
			(end 0.120396 0.2794)
			(stroke
				(width 0.1)
				(type default)
			)
			(layer "F.Fab")
		)
		(fp_line
			(start 0.120396 0.2794)
			(end -0.12065 0.2794)
			(stroke
				(width 0.1)
				(type default)
			)
			(layer "F.Fab")
		)
		(fp_line
			(start -0.12065 0.3048)
			(end -0.67945 0.3048)
			(stroke
				(width 0.1)
				(type default)
			)
			(layer "F.Fab")
		)
		(fp_line
			(start -0.12065 0.2794)
			(end -0.12065 0.3048)
			(stroke
				(width 0.1)
				(type default)
			)
			(layer "F.Fab")
		)
		(fp_line
			(start -0.12065 -0.2794)
			(end 0.12065 -0.2794)
			(stroke
				(width 0.1)
				(type default)
			)
			(layer "F.Fab")
		)
		(fp_line
			(start -0.12065 -0.305054)
			(end -0.12065 -0.2794)
			(stroke
				(width 0.1)
				(type default)
			)
			(layer "F.Fab")
		)
		(fp_line
			(start -0.67945 0.3048)
			(end -0.67945 -0.305054)
			(stroke
				(width 0.1)
				(type default)
			)
			(layer "F.Fab")
		)
		(fp_line
			(start -0.67945 -0.305054)
			(end -0.12065 -0.305054)
			(stroke
				(width 0.1)
				(type default)
			)
			(layer "F.Fab")
		)
		(pad "1" smd circle
			(at -0.40005 0 180)
			(size 0 0)
			(layers "F.Cu" "F.Mask" "F.Paste")
			(net "P3V3_AUX")
		)
		(pad "2" smd circle
			(at 0.40005 0 180)
			(size 0 0)
			(layers "F.Cu" "F.Mask" "F.Paste")
			(net "PWRGD_P1V8_AUX_R")
		)
	)
)
